FILE_TYPE = CONNECTIVITY;
{Allegro Design Entry HDL 17.2-2016 S081 (4005846) 1/11/2022}
"PAGE_NUMBER" = 52;
0"NC";
1"P12V_AUX\g";
2"P3V3_RGM\g";
3"P3V3_AUX\g";
4"P3V3_LDO\g";
5"P3V3_LDO\g";
6"P3V3_AUX\g";
7"P3V3_AUX\g";
8"GND\g";
9"GND\g";
10"GND\g";
11"GND\g";
12"GND\g";
13"GND\g";
14"GND\g";
15"GND\g";
16"GND\g";
17"GND\g";
18"GND\g";
19"GND\g";
20"GND\g";
21"GND\g";
22"GND\g";
23"GND\g";
24"GND\g";
25"GND\g";
26"GND\g";
27"EN_P3V3_RGM";
28"EN_P3V3_RGM_R";
29"PWRGD_P1V8_AUX_R3";
30"PWRGD_P3V3_AUX_R";
31"SW_P3V3_AUX_BST";
32"P3V3_AUX_MODE";
33"SW_P3V3_AUX_FLT";
34"EN_P3V3_R1";
35"EN_P3V3";
36"SW_P3V3_AUX_SW";
37"EN_P3V3_RGM";
38"PWRGD_P3V3_RGM_R";
39"PWRGD_P3V3_RGM_R3";
40"TP_U14_FLAG_N";
41"P3V3_AUX_FB_RC";
42"SW_P3V3_AUX_BST_R";
43"EN_P3V3";
44"PWRGD_P1V8_AUX";
45"PWRGD_EN_P3V3_R";
46"P3V3_AUX_REF";
47"P3V3_AUX_CS";
48"P3V3_AUX_VCC";
49"PWRGD_P1V8_AUX_R2";
50"PWRGD_P1V8_AUX";
51"PWRGD_P3V3_RGM";
52"PWRGD_P5V_AUX";
53"PWRGD_P3V3_AUX";
54"PWRGD_P5V_AUX";
%"UNIVERSAL_GND"
"1","(-3375,1925)","0","logical_power","I100";
;
HDL_POWER"GND"
CDS_LIB"logical_power";
"A"15;
%"Q_CAP"
"1","(-3375,2125)","0","pure_quanta","I101";
;
VALUE"0.1UF"
MATERIAL"X7R"
PACK_TYPE"0402"
VOLTAGE"25V"
PART_NUMBER"CH4104K1B00"
TOLERANCE"10%"
CDS_LIB"pure_quanta"
$LOCATION"C262"
CDS_LOCATION"C262"
$SEC"1"
CDS_SEC"1";
"B"
$PN"2"15;
"A"
$PN"1"1;
%"Q_CAP"
"1","(-2500,2050)","0","pure_quanta","I102";
;
VALUE"22UF"
PACK_TYPE"C0805"
VOLTAGE"16V"
PART_NUMBER"CH6223MEA01"
TOLERANCE"20%"
MATERIAL"X6S"
CDS_LIB"pure_quanta"
$LOCATION"C265"
CDS_LOCATION"C265"
$SEC"1"
CDS_SEC"1";
"B"
$PN"2"19;
"A"
$PN"1"33;
%"MC74VHC1G32DTT1G"
"1","(1725,2600)","0","pure_quanta","I104";
;
VALUE"MC74VHC1G32DTT1G"
PART_NUMBER"AL001G32031"
PART_TYPE"SMLF"
MATERIAL"IC"
NEEDS_NO_SIZE"TRUE"
CDS_LMAN_SYM_OUTLINE"-400,275,400,-275"
CDS_LIB"pure_quanta"
$LOCATION"U42"
CDS_LOCATION"U42"
$SEC"1"
CDS_SEC"1";
"VCC"
$PN"5"5;
"GND"
$PN"3"13;
"IN_A"
$PN"2"44;
"IN_B"
$PN"1"54;
"OUT_Y"
$PN"4"43;
%"Q_CAP"
"1","(2250,3100)","2","pure_quanta","I107";
;
TOLERANCE"10%"
VALUE"0.1UF"
VOLTAGE"25V"
MATERIAL"X7R"
PACK_TYPE"0402"
PART_NUMBER"CH4104K1B00"
CDS_LIB"pure_quanta"
$LOCATION"C297"
CDS_LOCATION"C297"
$SEC"1"
CDS_SEC"1";
"B"
$PN"2"14;
"A"
$PN"1"5;
%"UNIVERSAL_GND"
"1","(2250,2900)","0","logical_power","I109";
;
HDL_POWER"GND"
CDS_LIB"logical_power";
"A"14;
%"Q_CAP"
"1","(-1175,2050)","0","pure_quanta","I11";
;
VALUE"0.1UF"
VOLTAGE"25V"
PACK_TYPE"0402"
MATERIAL"X7R"
TOLERANCE"10%"
PART_NUMBER"CH4104K1B00"
SEC_TYPE"0402"
CDS_LIB"pure_quanta"
LOCATION"PC223"
SEC"1";
"B"
$PN"2"19;
"A"
$PN"1"33;
%"UNIVERSAL_GND"
"1","(1075,2300)","0","logical_power","I112";
;
CDS_LIB"logical_power"
HDL_POWER"GND";
"A"13;
%"74LVC1G08GW"
"1","(3600,-1400)","0","pure_quanta","I114";
;
PACK_TYPE"SM"
MATERIAL"IC"
VALUE"74LVC1G08GW"
PART_NUMBER"ALVC1G08009"
NEEDS_NO_SIZE"TRUE"
CDS_LIB"pure_quanta"
$LOCATION"U18"
CDS_LOCATION"U18"
$SEC"1"
CDS_SEC"1";
"VCC"
$PN"5"4;
"Y"
$PN"4"37;
"B"
$PN"1"52;
"A"
$PN"2"49;
"GND"
$PN"3"10;
%"UNIVERSAL_GND"
"1","(3900,-1100)","0","logical_power","I118";
;
CDS_LIB"logical_power"
HDL_POWER"GND";
"A"11;
%"Q_CAP"
"1","(3900,-925)","2","pure_quanta","I119";
;
PART_NUMBER"CH4104K1B00"
PACK_TYPE"0402"
MATERIAL"X7R"
VALUE"0.1UF"
TOLERANCE"10%"
VOLTAGE"25V"
CDS_LIB"pure_quanta"
$LOCATION"C296"
CDS_LOCATION"C296"
$SEC"1"
CDS_SEC"1";
"B"
$PN"2"11;
"A"
$PN"1"4;
%"UNIVERSAL_GND"
"1","(325,225)","0","logical_power","I12";
;
CDS_LIB"logical_power"
HDL_POWER"GND";
"A"16;
%"UNIVERSAL_GND"
"1","(3550,-1825)","0","logical_power","I120";
;
CDS_LIB"logical_power"
HDL_POWER"GND";
"A"10;
%"UNIVERSAL_GND"
"1","(2925,-1875)","0","logical_power","I124";
;
HDL_POWER"GND"
CDS_LIB"logical_power";
"A"9;
%"Q_CAP"
"1","(2925,-1650)","0","pure_quanta","I125";
;
VALUE"1UF"
PACK_TYPE"C0402"
MATERIAL"X6S"
VOLTAGE"25V"
TOLERANCE"10%"
PART_NUMBER"CH5104KEB02"
CDS_LIB"pure_quanta"
$LOCATION"C305"
CDS_LOCATION"C305"
$SEC"1"
CDS_SEC"1";
"B"
$PN"2"9;
"A"
$PN"1"49;
%"Q_RES"
"1","(2475,-1450)","0","pure_quanta","I127";
;
VALUE"100"
TOLERANCE"1%"
MATERIAL"CHIP"
WATTAGE"1/16W"
PART_NUMBER"CS11002FB07"
PACK_TYPE"0402LF"
CDS_LIB"pure_quanta"
$LOCATION"R529"
CDS_LOCATION"R529"
$SEC"1"
CDS_SEC"1";
"B"
$PN"2"49;
"A"
$PN"1"50;
%"Q_RES"
"2","(325,2075)","0","pure_quanta","I13";
;
VALUE"10K"
MATERIAL"CHIP"
PART_NUMBER"CS31002FB08"
PACK_TYPE"0402LF"
WATTAGE"1/16W"
TOLERANCE"1%"
SEC_TYPE"0402LF"
CDS_LIB"pure_quanta"
LOCATION"PR242"
SEC"1";
"A"
$PN"1"6;
"B"
$PN"2"30;
%"Q_RES"
"1","(-1625,1550)","0","pure_quanta","I137";
;
VALUE"0"
MATERIAL"EMPTY"
PART_NUMBER"CS00002JB13"
PACK_TYPE"0402LF"
WATTAGE"1/16W"
TOLERANCE"5%"
CDS_LIB"pure_quanta"
$LOCATION"R871"
CDS_LOCATION"R871"
$SEC"1"
CDS_SEC"1";
"B"
$PN"2"45;
"A"
$PN"1"34;
%"Q_RES"
"1","(-2500,-1550)","0","pure_quanta","I139";
;
PACK_TYPE"0402LF"
VALUE"0"
TOLERANCE"5%"
MATERIAL"EMPTY"
PART_NUMBER"CS00002JB13"
CDS_LIB"pure_quanta"
WATTAGE"1/16W"
$LOCATION"R869"
CDS_LOCATION"R869"
$SEC"1"
CDS_SEC"1";
"B"
$PN"2"28;
"A"
$PN"1"29;
%"Q_RES"
"1","(400,-1525)","0","pure_quanta","I141";
;
VALUE"0"
PACK_TYPE"0402LF"
MATERIAL"EMPTY"
PART_NUMBER"CS00002JB13"
CDS_LIB"pure_quanta"
TOLERANCE"5%"
WATTAGE"1/16W"
$LOCATION"R872"
CDS_LOCATION"R872"
$SEC"1"
CDS_SEC"1";
"B"
$PN"2"39;
"A"
$PN"1"38;
%"UNIVERSAL_POWER"
"1","(2250,3325)","0","logical_power","I143";
;
HDL_POWER"P3V3_LDO"
CDS_LIB"logical_power";
"A"5;
%"UNIVERSAL_POWER"
"1","(3900,-725)","0","logical_power","I144";
;
HDL_POWER"P3V3_LDO"
CDS_LIB"logical_power";
"A"4;
%"Q_RES"
"1","(-625,-1700)","0","pure_quanta","I145";
;
VALUE"2.2K"
MATERIAL"CHIP"
PACK_TYPE"0402LF"
WATTAGE"1/16W"
PART_NUMBER"CS22202JB07"
TOLERANCE"5%"
CDS_LIB"pure_quanta"
LOCATION"R709"
$SEC"1"
CDS_SEC"1";
"B"
$PN"2"38;
"A"
$PN"1"2;
%"Q_RES"
"1","(850,1625)","0","pure_quanta","I146";
;
MATERIAL"CHIP"
VALUE"2.2"
PACK_TYPE"0402LF"
TOLERANCE"1%"
PART_NUMBER"CS-2202FB01"
WATTAGE"1/16W"
CDS_LIB"pure_quanta"
LOCATION"R415"
$SEC"1"
CDS_SEC"1";
"B"
$PN"2"31;
"A"
$PN"1"42;
%"Q_RES"
"1","(-2500,-1800)","0","pure_quanta","I147";
;
PART_NUMBER"CS11002FB07"
MATERIAL"CHIP"
PACK_TYPE"0402LF"
WATTAGE"1/16W"
TOLERANCE"1%"
VALUE"100"
CDS_LIB"pure_quanta"
LOCATION"R380"
$SEC"1"
CDS_SEC"1";
"B"
$PN"2"28;
"A"
$PN"1"27;
%"Q_CAP"
"1","(1350,1475)","0","pure_quanta","I15";
;
TOLERANCE"10%"
MATERIAL"X7R"
PACK_TYPE"0402"
PART_NUMBER"CH4223K1B00"
VOLTAGE"16V"
VALUE"0.22UF"
CDS_LIB"pure_quanta"
SEC_TYPE"0402"
LOCATION"PC224"
SEC"1";
"B"
$PN"2"36;
"A"
$PN"1"31;
%"Q_RES"
"2","(1300,75)","6","pure_quanta","I17";
;
PART_NUMBER"CS31242FB02"
MATERIAL"CHIP"
PACK_TYPE"0402LF"
TOLERANCE"1%"
WATTAGE"1/16W"
VALUE"12.4K"
CDS_LIB"pure_quanta"
LOCATION"PR530"
$SEC"1"
CDS_SEC"1";
"A"
$PN"1"26;
"B"
$PN"2"41;
%"UNIVERSAL_GND"
"1","(1300,-200)","0","logical_power","I18";
;
HDL_POWER"GND"
CDS_LIB"logical_power";
"A"26;
%"VCCAUX15"
"1","(-3375,2650)","0","logical_power","I2";
;
HDL_POWER"P12V_AUX"
CDS_LIB"logical_power";
"A"1;
%"Q_CAP"
"1","(3175,1075)","0","pure_quanta","I23";
;
TOLERANCE"10%"
MATERIAL"X7R"
VOLTAGE"25V"
VALUE"0.1UF"
PART_NUMBER"CH4104K1B00"
PACK_TYPE"0402"
SEC_TYPE"0402"
CDS_LIB"pure_quanta"
LOCATION"PC225"
SEC"1";
"B"
$PN"2"17;
"A"
$PN"1"7;
%"Q_RES"
"1","(3200,475)","6","pure_quanta","I25";
;
PART_NUMBER"CS35602FB00"
VALUE"56K"
WATTAGE"1/16W"
MATERIAL"CHIP"
TOLERANCE"1%"
PACK_TYPE"0402LF"
CDS_LIB"pure_quanta"
LOCATION"PR534"
$SEC"1"
CDS_SEC"1";
"B"
$PN"2"7;
"A"
$PN"1"41;
%"UNIVERSAL_GND"
"1","(4475,750)","0","logical_power","I28";
;
CDS_LIB"logical_power"
HDL_POWER"GND";
"A"17;
%"VCCAUX15"
"1","(5125,1450)","0","logical_power","I31";
;
HDL_POWER"P3V3_AUX"
CDS_LIB"logical_power";
"A"7;
%"Q_INDUCTOR"
"1","(-2925,2325)","0","pure_quanta","I32";
;
PART_NUMBER"CX220TN1001"
PACK_TYPE"SMLF"
MATERIAL"IND"
VALUE"BLM18SN220TN1D/8000MA"
NEEDS_NO_SIZE"TRUE"
CDS_LIB"pure_quanta"
LOCATION"PL19"
$SEC"1"
CDS_SEC"1";
"1"
$PN"1"1;
"2"
$PN"2"33;
%"Q_CAP"
"1","(3650,1075)","0","pure_quanta","I35";
;
PACK_TYPE"C0805"
VALUE"22UF"
PART_NUMBER"CH6222MEA00"
MATERIAL"X6S"
VOLTAGE"10V"
TOLERANCE"20%"
CDS_LIB"pure_quanta"
LOCATION"PC226"
$SEC"1"
CDS_SEC"1";
"B"
$PN"2"17;
"A"
$PN"1"7;
%"Q_CAP"
"1","(4000,1075)","0","pure_quanta","I36";
;
PART_NUMBER"CH6222MEA00"
MATERIAL"X6S"
VOLTAGE"10V"
PACK_TYPE"C0805"
VALUE"22UF"
TOLERANCE"20%"
CDS_LIB"pure_quanta"
LOCATION"PC227"
$SEC"1"
CDS_SEC"1";
"B"
$PN"2"17;
"A"
$PN"1"7;
%"Q_CAP"
"1","(4325,1075)","0","pure_quanta","I37";
;
PACK_TYPE"C0805"
PART_NUMBER"CH6222MEA00"
VALUE"22UF"
MATERIAL"X6S"
VOLTAGE"10V"
TOLERANCE"20%"
CDS_LIB"pure_quanta"
LOCATION"PC228"
$SEC"1"
CDS_SEC"1";
"B"
$PN"2"17;
"A"
$PN"1"7;
%"Q_CAP"
"1","(4650,1075)","0","pure_quanta","I38";
;
PACK_TYPE"C0805"
VALUE"22UF"
PART_NUMBER"CH6222MEA00"
MATERIAL"X6S"
VOLTAGE"10V"
TOLERANCE"20%"
CDS_LIB"pure_quanta"
LOCATION"PC229"
$SEC"1"
CDS_SEC"1";
"B"
$PN"2"17;
"A"
$PN"1"7;
%"UNIVERSAL_POWER"
"1","(325,2275)","0","logical_power","I39";
;
HDL_POWER"P3V3_AUX"
CDS_LIB"logical_power";
"A"6;
%"UNIVERSAL_GND"
"1","(-1600,200)","0","logical_power","I4";
;
CDS_LIB"logical_power"
HDL_POWER"GND";
"A"18;
%"UNIVERSAL_GND"
"1","(-2125,1725)","0","logical_power","I5";
;
CDS_LIB"logical_power"
HDL_POWER"GND";
"A"19;
%"UNIVERSAL_GND"
"1","(-875,-2250)","0","logical_power","I62";
;
CDS_LIB"logical_power"
HDL_POWER"GND";
"A"20;
%"Q_CAP"
"1","(-1975,-1250)","0","pure_quanta","I63";
;
MATERIAL"X7R"
TOLERANCE"10%"
VOLTAGE"25V"
VALUE"0.1UF"
PACK_TYPE"0402"
CDS_LIB"pure_quanta"
PART_NUMBER"CH4104K1B00"
LOCATION"C240"
$SEC"1"
CDS_SEC"1";
"B"
$PN"2"21;
"A"
$PN"1"3;
%"UNIVERSAL_GND"
"1","(-1975,-1475)","0","logical_power","I64";
;
CDS_LIB"logical_power"
HDL_POWER"GND";
"A"21;
%"VCCAUX15"
"1","(-1700,-950)","0","logical_power","I65";
;
HDL_POWER"P3V3_AUX"
CDS_LIB"logical_power";
"A"3;
%"Q_CAP"
"1","(-775,-1300)","0","pure_quanta","I66";
;
TOLERANCE"10%"
PACK_TYPE"0402"
MATERIAL"X7R"
PART_NUMBER"CH4104K1B00"
VALUE"0.1UF"
VOLTAGE"25V"
CDS_LIB"pure_quanta"
LOCATION"C251"
$SEC"1"
CDS_SEC"1";
"B"
$PN"2"8;
"A"
$PN"1"2;
%"UNIVERSAL_GND"
"1","(-775,-1525)","0","logical_power","I67";
;
HDL_POWER"GND"
CDS_LIB"logical_power";
"A"8;
%"UNIVERSAL_POWER"
"1","(-900,-1025)","0","logical_power","I68";
;
HDL_POWER"P3V3_RGM"
CDS_LIB"logical_power";
"A"2;
%"Q_CAP"
"1","(-50,-2050)","0","pure_quanta","I73";
;
PACK_TYPE"C0402"
VOLTAGE"25V"
VALUE"1UF"
TOLERANCE"10%"
MATERIAL"EMPTY"
PART_NUMBER"CH5104KEB02"
CDS_LIB"pure_quanta"
SEC_TYPE"C0402"
LOCATION"C252"
SEC"1";
"B"
$PN"2"22;
"A"
$PN"1"38;
%"UNIVERSAL_GND"
"1","(-50,-2275)","0","logical_power","I74";
;
CDS_LIB"logical_power"
HDL_POWER"GND";
"A"22;
%"AP22811AW57"
"1","(-1275,-1750)","2","pure_quanta","I79";
;
MATERIAL"IC"
L"DELAY: 1.7MS"
PART_TYPE"SMLF"
VALUE"AP22811AW5-7"
PART_NUMBER"AL022811000"
CDS_LMAN_SYM_OUTLINE"-175,100,175,-100"
NEEDS_NO_SIZE"TRUE"
CDS_LIB"pure_quanta"
LOCATION"U14"
$SEC"1"
CDS_SEC"1";
"IN"
$PN"5"3;
"FLG# \B"
$PN"3"40;
"EN"
$PN"4"28;
"GND"
$PN"2"20;
"OUT"
$PN"1"2;
%"Q_CAP"
"1","(-2125,2050)","0","pure_quanta","I80";
;
VALUE"22UF"
VOLTAGE"16V"
TOLERANCE"20%"
MATERIAL"X6S"
PART_NUMBER"CH6223MEA01"
PACK_TYPE"C0805"
CDS_LIB"pure_quanta"
SEC_TYPE"C0805"
LOCATION"PC219"
SEC"1";
"B"
$PN"2"19;
"A"
$PN"1"33;
%"Q_CAP"
"1","(-1725,2050)","0","pure_quanta","I81";
;
VALUE"22UF"
TOLERANCE"20%"
VOLTAGE"16V"
MATERIAL"X6S"
PACK_TYPE"C0805"
PART_NUMBER"CH6223MEA01"
CDS_LIB"pure_quanta"
SEC_TYPE"C0805"
LOCATION"PC218"
SEC"1";
"B"
$PN"2"19;
"A"
$PN"1"33;
%"MPQ8626GDZ"
"1","(-275,1150)","0","pure_quanta","I82";
;
PART_TYPE"SMLF"
VALUE"MPQ8626GD-Z"
MATERIAL"IC"
PART_NUMBER"AL008626000"
CDS_LMAN_SYM_OUTLINE"-250,725,250,-725"
NEEDS_NO_SIZE"TRUE"
CDS_LIB"pure_quanta"
LOCATION"PU1"
$SEC"1"
CDS_SEC"1";
"SW1"
$PN"2"36;
"CS"
$PN"4"47;
"MODE"
$PN"12"32;
"TRK_REF"
$PN"8"46;
"SW2"
$PN"11"36;
"PGND1"
$PN"1"16;
"VCC"
$PN"13"48;
"AGND"
$PN"7"16;
"FB"
$PN"6"41;
"BST"
$PN"10"42;
"EN"
$PN"5"45;
"PGND2"
$PN"14"16;
"PGOOD"
$PN"9"30;
"VIN"
$PN"3"33;
%"UNIVERSAL_GND"
"1","(-1200,-150)","0","logical_power","I84";
;
CDS_LIB"logical_power"
HDL_POWER"GND";
"A"23;
%"UNIVERSAL_GND"
"1","(800,-150)","0","logical_power","I85";
;
CDS_LIB"logical_power"
HDL_POWER"GND";
"A"24;
%"Q_CAP"
"1","(800,150)","0","pure_quanta","I86";
;
VALUE"3300PF"
VOLTAGE"50V"
MATERIAL"X7R"
TOLERANCE"10%"
PART_NUMBER"TMP_QCH2336K1B12"
PACK_TYPE"0402"
CDS_LIB"pure_quanta"
LOCATION"PC273"
$SEC"1"
CDS_SEC"1";
"B"
$PN"2"24;
"A"
$PN"1"46;
%"Q_RES"
"2","(-1200,150)","6","pure_quanta","I87";
;
TOLERANCE"1%"
PACK_TYPE"0402LF"
WATTAGE"1/16W"
VALUE"5.49K"
PART_NUMBER"CS25492FB02"
MATERIAL"CHIP"
SEC_TYPE"0402LF"
CDS_LIB"pure_quanta"
LOCATION"PR276"
SEC"1";
"A"
$PN"1"23;
"B"
$PN"2"47;
%"Q_RES"
"2","(-2025,750)","6","pure_quanta","I88";
;
PACK_TYPE"0402LF"
MATERIAL"CHIP"
VALUE"60.4K"
TOLERANCE"1%"
WATTAGE"1/16W"
PART_NUMBER"CS36042FB04"
CDS_LIB"pure_quanta"
LOCATION"PR532"
$SEC"1"
CDS_SEC"1";
"A"
$PN"1"25;
"B"
$PN"2"32;
%"UNIVERSAL_GND"
"1","(-2025,450)","0","logical_power","I89";
;
CDS_LIB"logical_power"
HDL_POWER"GND";
"A"25;
%"Q_CAP"
"1","(-1600,500)","0","pure_quanta","I9";
;
PACK_TYPE"C0402"
VALUE"1UF"
VOLTAGE"25V"
PART_NUMBER"CH5104KEB02"
MATERIAL"X6S"
TOLERANCE"10%"
SEC_TYPE"C0402"
CDS_LIB"pure_quanta"
LOCATION"PC221"
SEC"1";
"B"
$PN"2"18;
"A"
$PN"1"48;
%"Q_CAP"
"2","(3200,125)","0","pure_quanta","I91";
;
PACK_TYPE"0402"
TOLERANCE"5%"
MATERIAL"NPO"
VALUE"100PF"
VOLTAGE"50V"
PART_NUMBER"CH11006JB00"
CDS_LIB"pure_quanta"
LOCATION"PC239"
$SEC"1"
CDS_SEC"1";
"A"
$PN"1"41;
"B"
$PN"2"7;
%"Q_INDUCTOR"
"1","(1850,1350)","0","pure_quanta","I92";
;
MATERIAL"IND"
PACK_TYPE"SMLF"
VALUE"3.3UH/6A"
PART_NUMBER"CV-3360MZ07"
CDS_LIB"pure_quanta"
NEEDS_NO_SIZE"TRUE"
LOCATION"PL35"
$SEC"1"
CDS_SEC"1";
"1"
$PN"1"36;
"2"
$PN"2"7;
%"Q_CAP"
"1","(2175,1625)","0","pure_quanta","I93";
;
PACK_TYPE"C0402"
MATERIAL"EMPTY"
PART_NUMBER"CH30106KB19"
TOLERANCE"10%"
VOLTAGE"50V"
VALUE"0.001UF"
CDS_LIB"pure_quanta"
LOCATION"C151"
$SEC"1"
CDS_SEC"1";
"B"
$PN"2"12;
"A"
$PN"1"30;
%"UNIVERSAL_GND"
"1","(2175,1425)","0","logical_power","I94";
;
CDS_LIB"logical_power"
HDL_POWER"GND";
"A"12;
%"Q_RES"
"1","(2975,1825)","0","pure_quanta","I95";
;
VALUE"0"
MATERIAL"CHIP"
TOLERANCE"5%"
PACK_TYPE"0402LF"
PART_NUMBER"CS00002JB13"
WATTAGE"1/16W"
CDS_LIB"pure_quanta"
LOCATION"R293"
$SEC"1"
CDS_SEC"1";
"B"
$PN"2"53;
"A"
$PN"1"30;
%"Q_RES"
"1","(400,-1700)","0","pure_quanta","I96";
;
MATERIAL"CHIP"
VALUE"0"
PACK_TYPE"0402LF"
PART_NUMBER"CS00002JB13"
CDS_LIB"pure_quanta"
WATTAGE"1/16W"
TOLERANCE"5%"
LOCATION"R99"
$SEC"1"
CDS_SEC"1";
"B"
$PN"2"51;
"A"
$PN"1"38;
%"Q_RES"
"1","(-1625,1325)","0","pure_quanta","I97";
;
TOLERANCE"5%"
WATTAGE"1/16W"
PART_NUMBER"CS00002JB13"
PACK_TYPE"0402LF"
VALUE"0"
MATERIAL"CHIP"
CDS_LIB"pure_quanta"
LOCATION"R381"
$SEC"1"
CDS_SEC"1";
"B"
$PN"2"45;
"A"
$PN"1"35;
END.
